(kicad_pcb
	(version 20260206)
	(generator "pcbnew")
	(generator_version "10.0")
	(general
		(thickness 1.6)
		(legacy_teardrops no)
	)
	(paper "A4")
	(title_block
		(title "03242023_DA0F0TMBIJ0_F0T_Motherboard_J_brd_V01_OCP.brd")
		(comment 1 "Grand Teton / footprint 652 of 6105 (J8), pads 225-291 of 291")
	)
	(layers
		(0 "F.Cu" signal "TOP")
		(4 "In1.Cu" signal "GND")
		(6 "In2.Cu" signal "IN1")
		(8 "In3.Cu" signal "GND1")
		(10 "In4.Cu" signal "IN2")
		(12 "In5.Cu" signal "GND2")
		(14 "In6.Cu" signal "IN3")
		(16 "In7.Cu" signal "GND3")
		(18 "In8.Cu" signal "VCC")
		(20 "In9.Cu" signal "VCC1")
		(22 "In10.Cu" signal "GND4")
		(24 "In11.Cu" signal "IN4")
		(26 "In12.Cu" signal "GND5")
		(28 "In13.Cu" signal "IN5")
		(30 "In14.Cu" signal "GND6")
		(32 "In15.Cu" signal "IN6")
		(34 "In16.Cu" signal "GND7")
		(2 "B.Cu" signal "BOTTOM")
		(9 "F.Adhes" user "F.Adhesive")
		(11 "B.Adhes" user "B.Adhesive")
		(13 "F.Paste" user "Package Geometry/Pastemask Top")
		(15 "B.Paste" user "Package Geometry/Pastemask Bottom")
		(5 "F.SilkS" user "Ref Des/Silkscreen Top")
		(7 "B.SilkS" user "Ref Des/Silkscreen Bottom")
		(1 "F.Mask" user "Board Geometry/Soldermask Top")
		(3 "B.Mask" user "Board Geometry/Soldermask Bottom")
		(17 "Dwgs.User" user "User.Drawings")
		(19 "Cmts.User" user "User.Comments")
		(21 "Eco1.User" user "User.Eco1")
		(23 "Eco2.User" user "User.Eco2")
		(25 "Edge.Cuts" user "Board Geometry/Outline")
		(27 "Margin" user)
		(31 "F.CrtYd" user "Package Geometry/Place Bound Top")
		(29 "B.CrtYd" user "Package Geometry/Place Bound Bottom")
		(35 "F.Fab" user "Ref Des/Assembly Top")
		(33 "B.Fab" user "Ref Des/Assembly Bottom")
	)
	(footprint ""
		(layer "F.Cu")
		(at 265.674348 -258.091686)
		(property "Reference" "J8"
			(at -3.683 -81.702148 0)
			(unlocked yes)
			(layer "F.SilkS")
			(effects
				(font
					(size 0.7874 0.5842)
					(thickness 0.1524)
				)
				(justify left)
			)
		)
		(property "Value" ""
			(at 0 0 0)
			(layer "F.Fab")
			(effects
				(font
					(size 1.27 1.27)
				)
			)
		)
		(duplicate_pad_numbers_are_jumpers no)
		(pad "225" smd rect
			(at 2.050034 9.774936 270)
			(size 0.519938 1.4986)
			(layers "F.Cu" "F.Mask" "F.Paste")
			(net "M_D_CPU0_SB_CA<5>")
		)
		(pad "226" smd rect
			(at 2.050034 10.625074 270)
			(size 0.519938 1.4986)
			(layers "F.Cu" "F.Mask" "F.Paste")
			(net "GND")
		)
		(pad "227" smd rect
			(at 2.050034 11.474958 270)
			(size 0.519938 1.4986)
			(layers "F.Cu" "F.Mask" "F.Paste")
			(net "M_D_CPU0_SB_PAR")
		)
		(pad "228" smd rect
			(at 2.050034 12.325096 270)
			(size 0.519938 1.4986)
			(layers "F.Cu" "F.Mask" "F.Paste")
			(net "GND")
		)
		(pad "229" smd rect
			(at 2.050034 13.17498 270)
			(size 0.519938 1.4986)
			(layers "F.Cu" "F.Mask" "F.Paste")
			(net "M_D_CPU0_SB_CS_N<3>")
		)
		(pad "230" smd rect
			(at 2.050034 14.025118 270)
			(size 0.519938 1.4986)
			(layers "F.Cu" "F.Mask" "F.Paste")
			(net "GND")
		)
		(pad "231" smd rect
			(at 2.050034 14.875002 270)
			(size 0.519938 1.4986)
			(layers "F.Cu" "F.Mask" "F.Paste")
			(net "TP_CHD_CPU0_DIMM2_FRU_5")
		)
		(pad "232" smd rect
			(at 2.050034 15.724886 270)
			(size 0.519938 1.4986)
			(layers "F.Cu" "F.Mask" "F.Paste")
			(net "TP_CHD_CPU0_DIMM2_FRU_6")
		)
		(pad "233" smd rect
			(at 2.050034 16.575024 270)
			(size 0.519938 1.4986)
			(layers "F.Cu" "F.Mask" "F.Paste")
			(net "GND")
		)
		(pad "234" smd rect
			(at 2.050034 17.424908 270)
			(size 0.519938 1.4986)
			(layers "F.Cu" "F.Mask" "F.Paste")
			(net "M_D_CPU0_SB_CB<6>")
		)
		(pad "235" smd rect
			(at 2.050034 18.275046 270)
			(size 0.519938 1.4986)
			(layers "F.Cu" "F.Mask" "F.Paste")
			(net "GND")
		)
		(pad "236" smd rect
			(at 2.050034 19.12493 270)
			(size 0.519938 1.4986)
			(layers "F.Cu" "F.Mask" "F.Paste")
			(net "M_D_CPU0_SB_CB<7>")
		)
		(pad "237" smd rect
			(at 2.050034 19.975068 270)
			(size 0.519938 1.4986)
			(layers "F.Cu" "F.Mask" "F.Paste")
			(net "GND")
		)
		(pad "238" smd rect
			(at 2.050034 20.824952 270)
			(size 0.519938 1.4986)
			(layers "F.Cu" "F.Mask" "F.Paste")
			(net "M_D_CPU0_SB_DQS_DN<4>")
		)
		(pad "239" smd rect
			(at 2.050034 21.67509 270)
			(size 0.519938 1.4986)
			(layers "F.Cu" "F.Mask" "F.Paste")
			(net "M_D_CPU0_SB_DQS_DP<4>")
		)
		(pad "240" smd rect
			(at 2.050034 22.524974 270)
			(size 0.519938 1.4986)
			(layers "F.Cu" "F.Mask" "F.Paste")
			(net "GND")
		)
		(pad "241" smd rect
			(at 2.050034 23.375112 270)
			(size 0.519938 1.4986)
			(layers "F.Cu" "F.Mask" "F.Paste")
			(net "M_D_CPU0_SB_CB<2>")
		)
		(pad "242" smd rect
			(at 2.050034 24.224996 270)
			(size 0.519938 1.4986)
			(layers "F.Cu" "F.Mask" "F.Paste")
			(net "GND")
		)
		(pad "243" smd rect
			(at 2.050034 25.07488 270)
			(size 0.519938 1.4986)
			(layers "F.Cu" "F.Mask" "F.Paste")
			(net "M_D_CPU0_SB_CB<3>")
		)
		(pad "244" smd rect
			(at 2.050034 25.925018 270)
			(size 0.519938 1.4986)
			(layers "F.Cu" "F.Mask" "F.Paste")
			(net "GND")
		)
		(pad "245" smd rect
			(at 2.050034 26.774902 270)
			(size 0.519938 1.4986)
			(layers "F.Cu" "F.Mask" "F.Paste")
			(net "M_D_CPU0_SB_DQ<2>")
		)
		(pad "246" smd rect
			(at 2.050034 27.62504 270)
			(size 0.519938 1.4986)
			(layers "F.Cu" "F.Mask" "F.Paste")
			(net "GND")
		)
		(pad "247" smd rect
			(at 2.050034 28.474924 270)
			(size 0.519938 1.4986)
			(layers "F.Cu" "F.Mask" "F.Paste")
			(net "M_D_CPU0_SB_DQ<3>")
		)
		(pad "248" smd rect
			(at 2.050034 29.325062 270)
			(size 0.519938 1.4986)
			(layers "F.Cu" "F.Mask" "F.Paste")
			(net "GND")
		)
		(pad "249" smd rect
			(at 2.050034 30.174946 270)
			(size 0.519938 1.4986)
			(layers "F.Cu" "F.Mask" "F.Paste")
			(net "M_D_CPU0_SB_DQS_DN<5>")
		)
		(pad "250" smd rect
			(at 2.050034 31.025084 270)
			(size 0.519938 1.4986)
			(layers "F.Cu" "F.Mask" "F.Paste")
			(net "M_D_CPU0_SB_DQS_DP<5>")
		)
		(pad "251" smd rect
			(at 2.050034 31.874968 270)
			(size 0.519938 1.4986)
			(layers "F.Cu" "F.Mask" "F.Paste")
			(net "GND")
		)
		(pad "252" smd rect
			(at 2.050034 32.725106 270)
			(size 0.519938 1.4986)
			(layers "F.Cu" "F.Mask" "F.Paste")
			(net "M_D_CPU0_SB_DQ<6>")
		)
		(pad "253" smd rect
			(at 2.050034 33.57499 270)
			(size 0.519938 1.4986)
			(layers "F.Cu" "F.Mask" "F.Paste")
			(net "GND")
		)
		(pad "254" smd rect
			(at 2.050034 34.425128 270)
			(size 0.519938 1.4986)
			(layers "F.Cu" "F.Mask" "F.Paste")
			(net "M_D_CPU0_SB_DQ<7>")
		)
		(pad "255" smd rect
			(at 2.050034 35.275012 270)
			(size 0.519938 1.4986)
			(layers "F.Cu" "F.Mask" "F.Paste")
			(net "GND")
		)
		(pad "256" smd rect
			(at 2.050034 36.124896 270)
			(size 0.519938 1.4986)
			(layers "F.Cu" "F.Mask" "F.Paste")
			(net "M_D_CPU0_SB_DQ<10>")
		)
		(pad "257" smd rect
			(at 2.050034 36.975034 270)
			(size 0.519938 1.4986)
			(layers "F.Cu" "F.Mask" "F.Paste")
			(net "GND")
		)
		(pad "258" smd rect
			(at 2.050034 37.824918 270)
			(size 0.519938 1.4986)
			(layers "F.Cu" "F.Mask" "F.Paste")
			(net "M_D_CPU0_SB_DQ<11>")
		)
		(pad "259" smd rect
			(at 2.050034 38.675056 270)
			(size 0.519938 1.4986)
			(layers "F.Cu" "F.Mask" "F.Paste")
			(net "GND")
		)
		(pad "260" smd rect
			(at 2.050034 39.52494 270)
			(size 0.519938 1.4986)
			(layers "F.Cu" "F.Mask" "F.Paste")
			(net "M_D_CPU0_SB_DQS_DN<6>")
		)
		(pad "261" smd rect
			(at 2.050034 40.375078 270)
			(size 0.519938 1.4986)
			(layers "F.Cu" "F.Mask" "F.Paste")
			(net "M_D_CPU0_SB_DQS_DP<6>")
		)
		(pad "262" smd rect
			(at 2.050034 41.224962 270)
			(size 0.519938 1.4986)
			(layers "F.Cu" "F.Mask" "F.Paste")
			(net "GND")
		)
		(pad "263" smd rect
			(at 2.050034 42.0751 270)
			(size 0.519938 1.4986)
			(layers "F.Cu" "F.Mask" "F.Paste")
			(net "M_D_CPU0_SB_DQ<14>")
		)
		(pad "264" smd rect
			(at 2.050034 42.924984 270)
			(size 0.519938 1.4986)
			(layers "F.Cu" "F.Mask" "F.Paste")
			(net "GND")
		)
		(pad "265" smd rect
			(at 2.050034 43.775122 270)
			(size 0.519938 1.4986)
			(layers "F.Cu" "F.Mask" "F.Paste")
			(net "M_D_CPU0_SB_DQ<15>")
		)
		(pad "266" smd rect
			(at 2.050034 44.625006 270)
			(size 0.519938 1.4986)
			(layers "F.Cu" "F.Mask" "F.Paste")
			(net "GND")
		)
		(pad "267" smd rect
			(at 2.050034 45.47489 270)
			(size 0.519938 1.4986)
			(layers "F.Cu" "F.Mask" "F.Paste")
			(net "M_D_CPU0_SB_DQ<18>")
		)
		(pad "268" smd rect
			(at 2.050034 46.325028 270)
			(size 0.519938 1.4986)
			(layers "F.Cu" "F.Mask" "F.Paste")
			(net "GND")
		)
		(pad "269" smd rect
			(at 2.050034 47.174912 270)
			(size 0.519938 1.4986)
			(layers "F.Cu" "F.Mask" "F.Paste")
			(net "M_D_CPU0_SB_DQ<19>")
		)
		(pad "270" smd rect
			(at 2.050034 48.02505 270)
			(size 0.519938 1.4986)
			(layers "F.Cu" "F.Mask" "F.Paste")
			(net "GND")
		)
		(pad "271" smd rect
			(at 2.050034 48.874934 270)
			(size 0.519938 1.4986)
			(layers "F.Cu" "F.Mask" "F.Paste")
			(net "M_D_CPU0_SB_DQS_DN<7>")
		)
		(pad "272" smd rect
			(at 2.050034 49.725072 270)
			(size 0.519938 1.4986)
			(layers "F.Cu" "F.Mask" "F.Paste")
			(net "M_D_CPU0_SB_DQS_DP<7>")
		)
		(pad "273" smd rect
			(at 2.050034 50.574956 270)
			(size 0.519938 1.4986)
			(layers "F.Cu" "F.Mask" "F.Paste")
			(net "GND")
		)
		(pad "274" smd rect
			(at 2.050034 51.425094 270)
			(size 0.519938 1.4986)
			(layers "F.Cu" "F.Mask" "F.Paste")
			(net "M_D_CPU0_SB_DQ<22>")
		)
		(pad "275" smd rect
			(at 2.050034 52.274978 270)
			(size 0.519938 1.4986)
			(layers "F.Cu" "F.Mask" "F.Paste")
			(net "GND")
		)
		(pad "276" smd rect
			(at 2.050034 53.125116 270)
			(size 0.519938 1.4986)
			(layers "F.Cu" "F.Mask" "F.Paste")
			(net "M_D_CPU0_SB_DQ<23>")
		)
		(pad "277" smd rect
			(at 2.050034 53.975 270)
			(size 0.519938 1.4986)
			(layers "F.Cu" "F.Mask" "F.Paste")
			(net "GND")
		)
		(pad "278" smd rect
			(at 2.050034 54.824884 270)
			(size 0.519938 1.4986)
			(layers "F.Cu" "F.Mask" "F.Paste")
			(net "M_D_CPU0_SB_DQ<26>")
		)
		(pad "279" smd rect
			(at 2.050034 55.675022 270)
			(size 0.519938 1.4986)
			(layers "F.Cu" "F.Mask" "F.Paste")
			(net "GND")
		)
		(pad "280" smd rect
			(at 2.050034 56.524906 270)
			(size 0.519938 1.4986)
			(layers "F.Cu" "F.Mask" "F.Paste")
			(net "M_D_CPU0_SB_DQ<27>")
		)
		(pad "281" smd rect
			(at 2.050034 57.375044 270)
			(size 0.519938 1.4986)
			(layers "F.Cu" "F.Mask" "F.Paste")
			(net "GND")
		)
		(pad "282" smd rect
			(at 2.050034 58.224928 270)
			(size 0.519938 1.4986)
			(layers "F.Cu" "F.Mask" "F.Paste")
			(net "M_D_CPU0_SB_DQS_DN<8>")
		)
		(pad "283" smd rect
			(at 2.050034 59.075066 270)
			(size 0.519938 1.4986)
			(layers "F.Cu" "F.Mask" "F.Paste")
			(net "M_D_CPU0_SB_DQS_DP<8>")
		)
		(pad "284" smd rect
			(at 2.050034 59.92495 270)
			(size 0.519938 1.4986)
			(layers "F.Cu" "F.Mask" "F.Paste")
			(net "GND")
		)
		(pad "285" smd rect
			(at 2.050034 60.775088 270)
			(size 0.519938 1.4986)
			(layers "F.Cu" "F.Mask" "F.Paste")
			(net "M_D_CPU0_SB_DQ<30>")
		)
		(pad "286" smd rect
			(at 2.050034 61.624972 270)
			(size 0.519938 1.4986)
			(layers "F.Cu" "F.Mask" "F.Paste")
			(net "GND")
		)
		(pad "287" smd rect
			(at 2.050034 62.47511 270)
			(size 0.519938 1.4986)
			(layers "F.Cu" "F.Mask" "F.Paste")
			(net "M_D_CPU0_SB_DQ<31>")
		)
		(pad "288" smd rect
			(at 2.050034 63.324994 270)
			(size 0.519938 1.4986)
			(layers "F.Cu" "F.Mask" "F.Paste")
			(net "GND")
		)
		(pad "G1" thru_hole oval
			(at 0 -68.97497)
			(size 2.8194 1.5748)
			(drill oval 2.4384 1.1938)
			(layers "*.Cu" "*.Mask")
			(remove_unused_layers no)
			(net "GND")
			(clearance 0.127)
			(thermal_gap 0.127)
		)
		(pad "G2" thru_hole oval
			(at 0 3.875024)
			(size 2.8194 1.5748)
			(drill oval 2.4384 1.1938)
			(layers "*.Cu" "*.Mask")
			(remove_unused_layers no)
			(net "GND")
			(clearance 0.127)
			(thermal_gap 0.127)
		)
		(pad "G3" thru_hole oval
			(at 0 68.97497)
			(size 2.8194 1.5748)
			(drill oval 2.4384 1.1938)
			(layers "*.Cu" "*.Mask")
			(remove_unused_layers no)
			(net "GND")
			(clearance 0.127)
			(thermal_gap 0.127)
		)
	)
)
